# T6G (Grand Teton) — schematic netlist excerpt (pin names and nets, part order shuffled) for the footprints in the layout excerpt that follows; sources: Cadence DE-HDL packaged netlist, KiCad conversion of 04192023_DAF0TMB3IC0_F0TG_MB_C_brd_V02_OCP.brd

C2511  Q_CAP  22UF 4V 20% X6S  pkg C0402  page 74 : A = PVDD11_S3_P1 ; B = GND
C2217  Q_CAP  22UF 4V 20% X6S  pkg C0402  page 69 : A = PVDDCR_CPU1_P0 ; B = GND

(kicad_pcb
	(version 20260206)
	(generator "pcbnew")
	(generator_version "10.0")
	(general
		(thickness 1.6)
		(legacy_teardrops no)
	)
	(paper "A4")
	(title_block
		(title "04192023_DAF0TMB3IC0_F0TG_MB_C_brd_V02_OCP.brd")
		(comment 1 "Grand Teton / footprints 7026-7027 of 8354")
	)
	(layers
		(0 "F.Cu" signal "TOP")
		(4 "In1.Cu" signal "GND")
		(6 "In2.Cu" signal "IN1")
		(8 "In3.Cu" signal "GND1")
		(10 "In4.Cu" signal "IN2")
		(12 "In5.Cu" signal "GND2")
		(14 "In6.Cu" signal "IN3")
		(16 "In7.Cu" signal "GND3")
		(18 "In8.Cu" signal "VCC")
		(20 "In9.Cu" signal "VCC1")
		(22 "In10.Cu" signal "GND4")
		(24 "In11.Cu" signal "IN4")
		(26 "In12.Cu" signal "GND5")
		(28 "In13.Cu" signal "IN5")
		(30 "In14.Cu" signal "GND6")
		(32 "In15.Cu" signal "IN6")
		(34 "In16.Cu" signal "GND7")
		(2 "B.Cu" signal "BOTTOM")
		(9 "F.Adhes" user "F.Adhesive")
		(11 "B.Adhes" user "B.Adhesive")
		(13 "F.Paste" user "Package Geometry/Pastemask Top")
		(15 "B.Paste" user "Package Geometry/Pastemask Bottom")
		(5 "F.SilkS" user "Ref Des/Silkscreen Top")
		(7 "B.SilkS" user "Ref Des/Silkscreen Bottom")
		(1 "F.Mask" user "Board Geometry/Soldermask Top")
		(3 "B.Mask" user "Board Geometry/Soldermask Bottom")
		(17 "Dwgs.User" user "User.Drawings")
		(19 "Cmts.User" user "User.Comments")
		(21 "Eco1.User" user "User.Eco1")
		(23 "Eco2.User" user "User.Eco2")
		(25 "Edge.Cuts" user "Board Geometry/Outline")
		(27 "Margin" user)
		(31 "F.CrtYd" user "Package Geometry/Place Bound Top")
		(29 "B.CrtYd" user "Package Geometry/Place Bound Bottom")
		(35 "F.Fab" user "Ref Des/Assembly Top")
		(33 "B.Fab" user "Ref Des/Assembly Bottom")
	)
	(footprint ""
		(layer "B.Cu")
		(at 347.389958 -268.41831 180)
		(property "Reference" "C2217"
			(at 0 0 0)
			(layer "B.SilkS")
			(hide yes)
			(effects
				(font
					(size 1.27 1.27)
				)
				(justify mirror)
			)
		)
		(property "Value" ""
			(at 0 0 0)
			(layer "B.Fab")
			(effects
				(font
					(size 1.27 1.27)
				)
				(justify mirror)
			)
		)
		(duplicate_pad_numbers_are_jumpers no)
		(fp_line
			(start 0.7874 0.4064)
			(end 0.7874 -0.4064)
			(stroke
				(width 0.1524)
				(type default)
			)
			(layer "B.SilkS")
		)
		(fp_line
			(start 0.7874 -0.4064)
			(end -0.7874 -0.4064)
			(stroke
				(width 0.1524)
				(type default)
			)
			(layer "B.SilkS")
		)
		(fp_line
			(start -0.7874 0.4064)
			(end 0.7874 0.4064)
			(stroke
				(width 0.1524)
				(type default)
			)
			(layer "B.SilkS")
		)
		(fp_line
			(start -0.7874 -0.4064)
			(end -0.7874 0.4064)
			(stroke
				(width 0.1524)
				(type default)
			)
			(layer "B.SilkS")
		)
		(fp_line
			(start 0.67945 0.3048)
			(end 0.67945 -0.305054)
			(stroke
				(width 0.1)
				(type default)
			)
			(layer "B.Fab")
		)
		(fp_line
			(start 0.67945 -0.305054)
			(end 0.12065 -0.305054)
			(stroke
				(width 0.1)
				(type default)
			)
			(layer "B.Fab")
		)
		(fp_line
			(start 0.12065 0.3048)
			(end 0.67945 0.3048)
			(stroke
				(width 0.1)
				(type default)
			)
			(layer "B.Fab")
		)
		(fp_line
			(start 0.12065 0.2794)
			(end 0.12065 0.3048)
			(stroke
				(width 0.1)
				(type default)
			)
			(layer "B.Fab")
		)
		(fp_line
			(start 0.12065 -0.2794)
			(end -0.12065 -0.2794)
			(stroke
				(width 0.1)
				(type default)
			)
			(layer "B.Fab")
		)
		(fp_line
			(start 0.12065 -0.305054)
			(end 0.12065 -0.2794)
			(stroke
				(width 0.1)
				(type default)
			)
			(layer "B.Fab")
		)
		(fp_line
			(start -0.120396 0.3048)
			(end -0.120396 0.2794)
			(stroke
				(width 0.1)
				(type default)
			)
			(layer "B.Fab")
		)
		(fp_line
			(start -0.120396 0.2794)
			(end 0.12065 0.2794)
			(stroke
				(width 0.1)
				(type default)
			)
			(layer "B.Fab")
		)
		(fp_line
			(start -0.12065 -0.2794)
			(end -0.12065 -0.3048)
			(stroke
				(width 0.1)
				(type default)
			)
			(layer "B.Fab")
		)
		(fp_line
			(start -0.12065 -0.3048)
			(end -0.67945 -0.3048)
			(stroke
				(width 0.1)
				(type default)
			)
			(layer "B.Fab")
		)
		(fp_line
			(start -0.67945 0.3048)
			(end -0.120396 0.3048)
			(stroke
				(width 0.1)
				(type default)
			)
			(layer "B.Fab")
		)
		(fp_line
			(start -0.67945 -0.3048)
			(end -0.67945 0.3048)
			(stroke
				(width 0.1)
				(type default)
			)
			(layer "B.Fab")
		)
		(pad "1" smd circle
			(at 0.40005 0)
			(size 0 0)
			(layers "B.Cu" "B.Mask" "B.Paste")
			(net "PVDDCR_CPU1_P0")
		)
		(pad "2" smd circle
			(at -0.40005 0)
			(size 0 0)
			(layers "B.Cu" "B.Mask" "B.Paste")
			(net "GND")
		)
	)
	(footprint ""
		(layer "B.Cu")
		(at 117.769386 -266.005564)
		(property "Reference" "C2511"
			(at 0 0 0)
			(layer "B.SilkS")
			(hide yes)
			(effects
				(font
					(size 1.27 1.27)
				)
				(justify mirror)
			)
		)
		(property "Value" ""
			(at 0 0 0)
			(layer "B.Fab")
			(effects
				(font
					(size 1.27 1.27)
				)
				(justify mirror)
			)
		)
		(duplicate_pad_numbers_are_jumpers no)
		(fp_line
			(start -0.7874 -0.4064)
			(end -0.7874 0.4064)
			(stroke
				(width 0.1524)
				(type default)
			)
			(layer "B.SilkS")
		)
		(fp_line
			(start -0.7874 0.4064)
			(end 0.7874 0.4064)
			(stroke
				(width 0.1524)
				(type default)
			)
			(layer "B.SilkS")
		)
		(fp_line
			(start 0.7874 -0.4064)
			(end -0.7874 -0.4064)
			(stroke
				(width 0.1524)
				(type default)
			)
			(layer "B.SilkS")
		)
		(fp_line
			(start 0.7874 0.4064)
			(end 0.7874 -0.4064)
			(stroke
				(width 0.1524)
				(type default)
			)
			(layer "B.SilkS")
		)
		(fp_line
			(start -0.67945 -0.3048)
			(end -0.67945 0.3048)
			(stroke
				(width 0.1)
				(type default)
			)
			(layer "B.Fab")
		)
		(fp_line
			(start -0.67945 0.3048)
			(end -0.120396 0.3048)
			(stroke
				(width 0.1)
				(type default)
			)
			(layer "B.Fab")
		)
		(fp_line
			(start -0.12065 -0.3048)
			(end -0.67945 -0.3048)
			(stroke
				(width 0.1)
				(type default)
			)
			(layer "B.Fab")
		)
		(fp_line
			(start -0.12065 -0.2794)
			(end -0.12065 -0.3048)
			(stroke
				(width 0.1)
				(type default)
			)
			(layer "B.Fab")
		)
		(fp_line
			(start -0.120396 0.2794)
			(end 0.12065 0.2794)
			(stroke
				(width 0.1)
				(type default)
			)
			(layer "B.Fab")
		)
		(fp_line
			(start -0.120396 0.3048)
			(end -0.120396 0.2794)
			(stroke
				(width 0.1)
				(type default)
			)
			(layer "B.Fab")
		)
		(fp_line
			(start 0.12065 -0.305054)
			(end 0.12065 -0.2794)
			(stroke
				(width 0.1)
				(type default)
			)
			(layer "B.Fab")
		)
		(fp_line
			(start 0.12065 -0.2794)
			(end -0.12065 -0.2794)
			(stroke
				(width 0.1)
				(type default)
			)
			(layer "B.Fab")
		)
		(fp_line
			(start 0.12065 0.2794)
			(end 0.12065 0.3048)
			(stroke
				(width 0.1)
				(type default)
			)
			(layer "B.Fab")
		)
		(fp_line
			(start 0.12065 0.3048)
			(end 0.67945 0.3048)
			(stroke
				(width 0.1)
				(type default)
			)
			(layer "B.Fab")
		)
		(fp_line
			(start 0.67945 -0.305054)
			(end 0.12065 -0.305054)
			(stroke
				(width 0.1)
				(type default)
			)
			(layer "B.Fab")
		)
		(fp_line
			(start 0.67945 0.3048)
			(end 0.67945 -0.305054)
			(stroke
				(width 0.1)
				(type default)
			)
			(layer "B.Fab")
		)
		(pad "1" smd circle
			(at 0.40005 0 180)
			(size 0 0)
			(layers "B.Cu" "B.Mask" "B.Paste")
			(net "PVDD11_S3_P1")
		)
		(pad "2" smd circle
			(at -0.40005 0 180)
			(size 0 0)
			(layers "B.Cu" "B.Mask" "B.Paste")
			(net "GND")
		)
	)
)
